FILE_TYPE=LIBRARY_PARTS;
primitive 'MPQ8626GDZ';
  pin
    'VIN':
      PIN_NUMBER='(3)';
      INPUT_LOAD='(-0.01,0.01)';
    'PGOOD':
      PIN_NUMBER='(9)';
      OUTPUT_LOAD='(1.0,-1.0)';
    'PGND2':
      PIN_NUMBER='(14)';
      PINUSE='POWER';
      NO_LOAD_CHECK='Both';
      NO_IO_CHECK='Both';
      NO_ASSERT_CHECK='TRUE';
      NO_DIR_CHECK='TRUE';
      ALLOW_CONNECT='TRUE';
    'EN':
      PIN_NUMBER='(5)';
      INPUT_LOAD='(-0.01,0.01)';
    'BST':
      PIN_NUMBER='(10)';
      INPUT_LOAD='(-0.01,0.01)';
    'FB':
      PIN_NUMBER='(6)';
      INPUT_LOAD='(-0.01,0.01)';
    'AGND':
      PIN_NUMBER='(7)';
      PINUSE='POWER';
      NO_LOAD_CHECK='Both';
      NO_IO_CHECK='Both';
      NO_ASSERT_CHECK='TRUE';
      NO_DIR_CHECK='TRUE';
      ALLOW_CONNECT='TRUE';
    'VCC':
      PIN_NUMBER='(13)';
      OUTPUT_LOAD='(1.0,-1.0)';
    'PGND1':
      PIN_NUMBER='(1)';
      PINUSE='POWER';
      NO_LOAD_CHECK='Both';
      NO_IO_CHECK='Both';
      NO_ASSERT_CHECK='TRUE';
      NO_DIR_CHECK='TRUE';
      ALLOW_CONNECT='TRUE';
    'SW2':
      PIN_NUMBER='(11)';
      OUTPUT_LOAD='(1.0,-1.0)';
    'TRK_REF':
      PIN_NUMBER='(8)';
      INPUT_LOAD='(-0.01,0.01)';
    'MODE':
      PIN_NUMBER='(12)';
      INPUT_LOAD='(-0.01,0.01)';
    'CS':
      PIN_NUMBER='(4)';
      INPUT_LOAD='(-0.01,0.01)';
    'SW1':
      PIN_NUMBER='(2)';
      OUTPUT_LOAD='(1.0,-1.0)';
  end_pin;
  body
    PART_NAME='MPQ8626GDZ';
    BODY_NAME='MPQ8626GDZ';
    PHYS_DES_PREFIX='U';
    CLASS='IC';
  end_body;
end_primitive;

END.
